#ISCELL
  mstr_misc dns *
  *
#ISCELL
  pure_quanta quanta_title_block_c *
  *
#ISCELL
  pure_quanta_power universal_gnd *
  page198_i1
#CELL
  pure_quanta q_cap *
  page198_i10
#ISCELL
  pure_quanta_power universal_gnd *
  page198_i11
#CELL
  pure_quanta q_res *
  page198_i12
#CELL
  pure_quanta q_cap *
  page198_i13
#ISCELL
  pure_quanta_power vcc_core *
  page198_i14
#CELL
  pure_quanta isl99390frztr5935 *
  page198_i15
#ISCELL
  pure_quanta_power universal_gnd *
  page198_i16
#CELL
  pure_quanta q_res *
  page198_i17
#CELL
  pure_quanta q_cap *
  page198_i18
#ISCELL
  pure_quanta_power universal_gnd *
  page198_i19
#CELL
  pure_quanta q_cap *
  page198_i2
#CELL
  pure_quanta q_cap *
  page198_i20
#ISCELL
  pure_quanta_power universal_gnd *
  page198_i21
#CELL
  pure_quanta q_res *
  page198_i22
#ISCELL
  standard offpage *
  page198_i23
#ISCELL
  standard offpage *
  page198_i24
#ISCELL
  standard offpage *
  page198_i25
#ISCELL
  standard offpage *
  page198_i26
#ISCELL
  pure_quanta_power universal_gnd *
  page198_i27
#CELL
  pure_quanta q_cap *
  page198_i28
#CELL
  pure_quanta q_res *
  page198_i29
#ISCELL
  pure_quanta_power universal_gnd *
  page198_i3
#ISCELL
  pure_quanta_power universal_gnd *
  page198_i30
#CELL
  pure_quanta q_cap *
  page198_i31
#ISCELL
  pure_quanta_power vcc_core *
  page198_i32
#ISCELL
  pure_quanta_power universal_gnd *
  page198_i33
#CELL
  pure_quanta q_res *
  page198_i34
#CELL
  pure_quanta q_cap *
  page198_i35
#CELL
  pure_quanta q_cap *
  page198_i36
#CELL
  pure_quanta q_cap *
  page198_i37
#ISCELL
  pure_quanta_power universal_gnd *
  page198_i38
#CELL
  pure_quanta q_res *
  page198_i39
#CELL
  pure_quanta q_res *
  page198_i4
#ISCELL
  pure_quanta_power universal_gnd *
  page198_i40
#CELL
  pure_quanta q_res *
  page198_i41
#CELL
  pure_quanta q_inductor4p_14 *
  page198_i42
#CELL
  pure_quanta q_inductor *
  page198_i43
#CELL
  pure_quanta q_cap *
  page198_i44
#CELL
  pure_quanta q_cap *
  page198_i45
#CELL
  pure_quanta q_cap *
  page198_i46
#ISCELL
  pure_quanta_power universal_gnd *
  page198_i47
#CELL
  pure_quanta q_cap *
  page198_i48
#ISCELL
  pure_quanta_power vcc_core *
  page198_i49
#ISCELL
  standard offpage *
  page198_i5
#ISCELL
  standard offpage *
  page198_i50
#CELL
  pure_quanta q_cap *
  page198_i51
#ISCELL
  pure_quanta_power universal_gnd *
  page198_i52
#CELL
  pure_quanta q_cap *
  page198_i53
#ISCELL
  pure_quanta_power vcc_core *
  page198_i54
#CELL
  pure_quanta q_res *
  page198_i55
#ISCELL
  pure_quanta_power universal_gnd *
  page198_i56
#CELL
  pure_quanta q_res *
  page198_i57
#CELL
  pure_quanta q_cap *
  page198_i58
#ISCELL
  standard offpage *
  page198_i59
#ISCELL
  standard offpage *
  page198_i6
#CELL
  pure_quanta q_cap *
  page198_i60
#CELL
  pure_quanta q_cap *
  page198_i61
#CELL
  pure_quanta q_inductor4p_14 *
  page198_i62
#CELL
  pure_quanta q_cap *
  page198_i63
#ISCELL
  pure_quanta_power universal_gnd *
  page198_i64
#CELL
  pure_quanta q_cap *
  page198_i65
#ISCELL
  pure_quanta_power vcc_core *
  page198_i66
#ISCELL
  standard offpage *
  page198_i67
#CELL
  pure_quanta q_cap *
  page198_i68
#ISCELL
  pure_quanta_power universal_gnd *
  page198_i69
#ISCELL
  standard offpage *
  page198_i7
#CELL
  pure_quanta q_cap *
  page198_i70
#ISCELL
  pure_quanta_power vcc_core *
  page198_i71
#CELL
  pure_quanta q_cap *
  page198_i72
#CELL
  pure_quanta isl99390frztr5935 *
  page198_i73
#ISCELL
  standard offpage *
  page198_i8
#ISCELL
  pure_quanta_power universal_gnd *
  page198_i9
